# T6G (Grand Teton) — schematic netlist excerpt (pin names and nets, part order shuffled) for the footprints in the layout excerpt that follows; sources: Cadence DE-HDL packaged netlist, KiCad conversion of 04192023_DAF0TMB3IC0_F0TG_MB_C_brd_V02_OCP.brd

PR348  Q_RES  5.6 1% CHIP  pkg 0402LF  page 195 : A = SW_PVDDCR_CPU0_P0_BOOT3 ; B = SW_PVDDCR_CPU0_P0_BOOT3_RC
R6706  Q_RES  1K 1% CHIP  pkg 0201LF  page 185 : A = P1V8_CPU1_RT_1D ; B = SMB_RT_CPU1_P0_ROM_R_SCL
R6318  Q_RES  90.9K 1% CHIP  pkg 0402LF  page 178 : A = P5V_AUX ; B = USB_HUB2_TI_USB_VBUS

(kicad_pcb
	(version 20260206)
	(generator "pcbnew")
	(generator_version "10.0")
	(general
		(thickness 1.6)
		(legacy_teardrops no)
	)
	(paper "A4")
	(title_block
		(title "04192023_DAF0TMB3IC0_F0TG_MB_C_brd_V02_OCP.brd")
		(comment 1 "Grand Teton / footprints 1680-1682 of 8354")
	)
	(layers
		(0 "F.Cu" signal "TOP")
		(4 "In1.Cu" signal "GND")
		(6 "In2.Cu" signal "IN1")
		(8 "In3.Cu" signal "GND1")
		(10 "In4.Cu" signal "IN2")
		(12 "In5.Cu" signal "GND2")
		(14 "In6.Cu" signal "IN3")
		(16 "In7.Cu" signal "GND3")
		(18 "In8.Cu" signal "VCC")
		(20 "In9.Cu" signal "VCC1")
		(22 "In10.Cu" signal "GND4")
		(24 "In11.Cu" signal "IN4")
		(26 "In12.Cu" signal "GND5")
		(28 "In13.Cu" signal "IN5")
		(30 "In14.Cu" signal "GND6")
		(32 "In15.Cu" signal "IN6")
		(34 "In16.Cu" signal "GND7")
		(2 "B.Cu" signal "BOTTOM")
		(9 "F.Adhes" user "F.Adhesive")
		(11 "B.Adhes" user "B.Adhesive")
		(13 "F.Paste" user "Package Geometry/Pastemask Top")
		(15 "B.Paste" user "Package Geometry/Pastemask Bottom")
		(5 "F.SilkS" user "Ref Des/Silkscreen Top")
		(7 "B.SilkS" user "Ref Des/Silkscreen Bottom")
		(1 "F.Mask" user "Board Geometry/Soldermask Top")
		(3 "B.Mask" user "Board Geometry/Soldermask Bottom")
		(17 "Dwgs.User" user "User.Drawings")
		(19 "Cmts.User" user "User.Comments")
		(21 "Eco1.User" user "User.Eco1")
		(23 "Eco2.User" user "User.Eco2")
		(25 "Edge.Cuts" user "Board Geometry/Outline")
		(27 "Margin" user)
		(31 "F.CrtYd" user "Package Geometry/Place Bound Top")
		(29 "B.CrtYd" user "Package Geometry/Place Bound Bottom")
		(35 "F.Fab" user "Ref Des/Assembly Top")
		(33 "B.Fab" user "Ref Des/Assembly Bottom")
	)
	(footprint ""
		(layer "F.Cu")
		(at 380.318772 -178.0921 -90)
		(property "Reference" "PR348"
			(at 0 0 270)
			(layer "F.SilkS")
			(hide yes)
			(effects
				(font
					(size 1.27 1.27)
				)
			)
		)
		(property "Value" ""
			(at 0 0 270)
			(layer "F.Fab")
			(effects
				(font
					(size 1.27 1.27)
				)
			)
		)
		(duplicate_pad_numbers_are_jumpers no)
		(fp_line
			(start -0.7874 0.4064)
			(end -0.7874 -0.4064)
			(stroke
				(width 0.1524)
				(type default)
			)
			(layer "F.SilkS")
		)
		(fp_line
			(start 0.7874 0.4064)
			(end -0.7874 0.4064)
			(stroke
				(width 0.1524)
				(type default)
			)
			(layer "F.SilkS")
		)
		(fp_line
			(start -0.7874 -0.4064)
			(end 0.7874 -0.4064)
			(stroke
				(width 0.1524)
				(type default)
			)
			(layer "F.SilkS")
		)
		(fp_line
			(start 0.7874 -0.4064)
			(end 0.7874 0.4064)
			(stroke
				(width 0.1524)
				(type default)
			)
			(layer "F.SilkS")
		)
		(fp_line
			(start -0.67945 0.3048)
			(end -0.67945 -0.305054)
			(stroke
				(width 0.1)
				(type default)
			)
			(layer "F.Fab")
		)
		(fp_line
			(start -0.12065 0.3048)
			(end -0.67945 0.3048)
			(stroke
				(width 0.1)
				(type default)
			)
			(layer "F.Fab")
		)
		(fp_line
			(start 0.120396 0.3048)
			(end 0.120396 0.2794)
			(stroke
				(width 0.1)
				(type default)
			)
			(layer "F.Fab")
		)
		(fp_line
			(start 0.67945 0.3048)
			(end 0.120396 0.3048)
			(stroke
				(width 0.1)
				(type default)
			)
			(layer "F.Fab")
		)
		(fp_line
			(start -0.12065 0.2794)
			(end -0.12065 0.3048)
			(stroke
				(width 0.1)
				(type default)
			)
			(layer "F.Fab")
		)
		(fp_line
			(start 0.120396 0.2794)
			(end -0.12065 0.2794)
			(stroke
				(width 0.1)
				(type default)
			)
			(layer "F.Fab")
		)
		(fp_line
			(start -0.12065 -0.2794)
			(end 0.12065 -0.2794)
			(stroke
				(width 0.1)
				(type default)
			)
			(layer "F.Fab")
		)
		(fp_line
			(start 0.12065 -0.2794)
			(end 0.12065 -0.3048)
			(stroke
				(width 0.1)
				(type default)
			)
			(layer "F.Fab")
		)
		(fp_line
			(start 0.12065 -0.3048)
			(end 0.67945 -0.3048)
			(stroke
				(width 0.1)
				(type default)
			)
			(layer "F.Fab")
		)
		(fp_line
			(start 0.67945 -0.3048)
			(end 0.67945 0.3048)
			(stroke
				(width 0.1)
				(type default)
			)
			(layer "F.Fab")
		)
		(fp_line
			(start -0.67945 -0.305054)
			(end -0.12065 -0.305054)
			(stroke
				(width 0.1)
				(type default)
			)
			(layer "F.Fab")
		)
		(fp_line
			(start -0.12065 -0.305054)
			(end -0.12065 -0.2794)
			(stroke
				(width 0.1)
				(type default)
			)
			(layer "F.Fab")
		)
		(pad "1" smd circle
			(at -0.40005 0 270)
			(size 0 0)
			(layers "F.Cu" "F.Mask" "F.Paste")
			(net "SW_PVDDCR_CPU0_P0_BOOT3")
		)
		(pad "2" smd circle
			(at 0.40005 0 270)
			(size 0 0)
			(layers "F.Cu" "F.Mask" "F.Paste")
			(net "SW_PVDDCR_CPU0_P0_BOOT3_RC")
		)
	)
	(footprint ""
		(layer "F.Cu")
		(at 103.145844 -394.68806 90)
		(property "Reference" "R6706"
			(at 0 0 90)
			(layer "F.SilkS")
			(hide yes)
			(effects
				(font
					(size 1.27 1.27)
				)
			)
		)
		(property "Value" ""
			(at 0 0 90)
			(layer "F.Fab")
			(effects
				(font
					(size 1.27 1.27)
				)
			)
		)
		(duplicate_pad_numbers_are_jumpers no)
		(fp_line
			(start 0.32512 -0.175006)
			(end 0.32512 0.175006)
			(stroke
				(width 0.1)
				(type default)
			)
			(layer "F.Fab")
		)
		(fp_line
			(start -0.32512 -0.175006)
			(end 0.32512 -0.175006)
			(stroke
				(width 0.1)
				(type default)
			)
			(layer "F.Fab")
		)
		(fp_line
			(start 0.32512 0.175006)
			(end -0.32512 0.175006)
			(stroke
				(width 0.1)
				(type default)
			)
			(layer "F.Fab")
		)
		(fp_line
			(start -0.32512 0.175006)
			(end -0.32512 -0.175006)
			(stroke
				(width 0.1)
				(type default)
			)
			(layer "F.Fab")
		)
		(pad "1" smd rect
			(at -0.2667 0 90)
			(size 0.3048 0.381)
			(layers "F.Cu" "F.Mask" "F.Paste")
			(net "P1V8_CPU1_RT_1D")
		)
		(pad "2" smd rect
			(at 0.2667 0 270)
			(size 0.3048 0.381)
			(layers "F.Cu" "F.Mask" "F.Paste")
			(net "SMB_RT_CPU1_P0_ROM_R_SCL")
		)
	)
	(footprint ""
		(layer "F.Cu")
		(at 104.469946 -52.86248 90)
		(property "Reference" "R6318"
			(at 0 0 90)
			(layer "F.SilkS")
			(hide yes)
			(effects
				(font
					(size 1.27 1.27)
				)
			)
		)
		(property "Value" ""
			(at 0 0 90)
			(layer "F.Fab")
			(effects
				(font
					(size 1.27 1.27)
				)
			)
		)
		(duplicate_pad_numbers_are_jumpers no)
		(fp_line
			(start 0.7874 -0.4064)
			(end 0.7874 0.4064)
			(stroke
				(width 0.1524)
				(type default)
			)
			(layer "F.SilkS")
		)
		(fp_line
			(start -0.7874 -0.4064)
			(end 0.7874 -0.4064)
			(stroke
				(width 0.1524)
				(type default)
			)
			(layer "F.SilkS")
		)
		(fp_line
			(start 0.7874 0.4064)
			(end -0.7874 0.4064)
			(stroke
				(width 0.1524)
				(type default)
			)
			(layer "F.SilkS")
		)
		(fp_line
			(start -0.7874 0.4064)
			(end -0.7874 -0.4064)
			(stroke
				(width 0.1524)
				(type default)
			)
			(layer "F.SilkS")
		)
		(fp_line
			(start -0.12065 -0.305054)
			(end -0.12065 -0.2794)
			(stroke
				(width 0.1)
				(type default)
			)
			(layer "F.Fab")
		)
		(fp_line
			(start -0.67945 -0.305054)
			(end -0.12065 -0.305054)
			(stroke
				(width 0.1)
				(type default)
			)
			(layer "F.Fab")
		)
		(fp_line
			(start 0.67945 -0.3048)
			(end 0.67945 0.3048)
			(stroke
				(width 0.1)
				(type default)
			)
			(layer "F.Fab")
		)
		(fp_line
			(start 0.12065 -0.3048)
			(end 0.67945 -0.3048)
			(stroke
				(width 0.1)
				(type default)
			)
			(layer "F.Fab")
		)
		(fp_line
			(start 0.12065 -0.2794)
			(end 0.12065 -0.3048)
			(stroke
				(width 0.1)
				(type default)
			)
			(layer "F.Fab")
		)
		(fp_line
			(start -0.12065 -0.2794)
			(end 0.12065 -0.2794)
			(stroke
				(width 0.1)
				(type default)
			)
			(layer "F.Fab")
		)
		(fp_line
			(start 0.120396 0.2794)
			(end -0.12065 0.2794)
			(stroke
				(width 0.1)
				(type default)
			)
			(layer "F.Fab")
		)
		(fp_line
			(start -0.12065 0.2794)
			(end -0.12065 0.3048)
			(stroke
				(width 0.1)
				(type default)
			)
			(layer "F.Fab")
		)
		(fp_line
			(start 0.67945 0.3048)
			(end 0.120396 0.3048)
			(stroke
				(width 0.1)
				(type default)
			)
			(layer "F.Fab")
		)
		(fp_line
			(start 0.120396 0.3048)
			(end 0.120396 0.2794)
			(stroke
				(width 0.1)
				(type default)
			)
			(layer "F.Fab")
		)
		(fp_line
			(start -0.12065 0.3048)
			(end -0.67945 0.3048)
			(stroke
				(width 0.1)
				(type default)
			)
			(layer "F.Fab")
		)
		(fp_line
			(start -0.67945 0.3048)
			(end -0.67945 -0.305054)
			(stroke
				(width 0.1)
				(type default)
			)
			(layer "F.Fab")
		)
		(pad "1" smd circle
			(at -0.40005 0 90)
			(size 0 0)
			(layers "F.Cu" "F.Mask" "F.Paste")
			(net "P5V_AUX")
		)
		(pad "2" smd circle
			(at 0.40005 0 90)
			(size 0 0)
			(layers "F.Cu" "F.Mask" "F.Paste")
			(net "USB_HUB2_TI_USB_VBUS")
		)
	)
)
